#ISCELL
  mstr_misc dns *
  *
#ISCELL
  pure_quanta quanta_title_block_c *
  *
#ISCELL
  logical_power universal_gnd *
  page268_i1
#CELL
  pure_quanta q_res *
  page268_i10
#CELL
  pure_quanta q_res *
  page268_i11
#ISCELL
  logical_power universal_gnd *
  page268_i12
#CELL
  pure_quanta q_cap *
  page268_i13
#ISCELL
  logical_power vccaux15 *
  page268_i14
#CELL
  pure_quanta q_cap *
  page268_i15
#ISCELL
  logical_power vccaux15 *
  page268_i16
#ISCELL
  logical_power universal_gnd *
  page268_i17
#ISCELL
  logical_power universal_gnd *
  page268_i18
#CELL
  pure_quanta q_res *
  page268_i19
#ISCELL
  standard offpage *
  page268_i2
#ISCELL
  logical_power universal_gnd *
  page268_i20
#CELL
  pure_quanta q_res *
  page268_i21
#CELL
  pure_quanta rs53317lr *
  page268_i22
#CELL
  pure_quanta q_cap *
  page268_i23
#ISCELL
  logical_power universal_gnd *
  page268_i24
#CELL
  pure_quanta q_cap *
  page268_i25
#CELL
  pure_quanta q_cap *
  page268_i26
#CELL
  pure_quanta q_res *
  page268_i27
#CELL
  pure_quanta q_res *
  page268_i28
#CELL
  pure_quanta q_inductor *
  page268_i29
#ISCELL
  logical_power vccaux15 *
  page268_i3
#ISCELL
  logical_power universal_gnd *
  page268_i30
#CELL
  pure_quanta q_cap *
  page268_i31
#CELL
  pure_quanta q_res *
  page268_i32
#CELL
  pure_quanta q_res *
  page268_i33
#ISCELL
  logical_power vccaux15 *
  page268_i34
#CELL
  pure_quanta q_cap *
  page268_i35
#CELL
  pure_quanta q_res *
  page268_i36
#CELL
  pure_quanta q_cap *
  page268_i37
#CELL
  pure_quanta q_cap *
  page268_i38
#CELL
  pure_quanta q_cap *
  page268_i39
#CELL
  pure_quanta q_cap *
  page268_i4
#CELL
  pure_quanta q_res *
  page268_i40
#CELL
  pure_quanta q_res *
  page268_i41
#CELL
  pure_quanta q_cap *
  page268_i42
#CELL
  pure_quanta q_cap *
  page268_i43
#ISCELL
  standard offpage *
  page268_i44
#ISCELL
  logical_power universal_gnd *
  page268_i45
#ISCELL
  logical_power vccaux15 *
  page268_i46
#CELL
  pure_quanta q_cap *
  page268_i47
#ISCELL
  logical_power vccaux15 *
  page268_i48
#CELL
  pure_quanta q_res *
  page268_i5
#ISCELL
  logical_power universal_gnd *
  page268_i6
#CELL
  pure_quanta q_cap *
  page268_i7
#ISCELL
  logical_power universal_gnd *
  page268_i8
#CELL
  pure_quanta q_res *
  page268_i9
